(kicad_pcb
	(version 20221018)
	(generator pcbnew)
	(general
    (thickness 1.7403)
  )
	(paper "A4")
	(title_block
    (title "Data Center RDIMM DDR4 Tester")
    (date "2024-09-30")
    (rev "1.2.4")
		(comment 9 "footprints 467-475 of 690")
	)
	(layers
    (0 "F.Cu" signal)
    (1 "In1.Cu" power)
    (2 "In2.Cu" signal)
    (3 "In3.Cu" power)
    (4 "In4.Cu" power)
    (5 "In5.Cu" signal)
    (6 "In6.Cu" power)
    (7 "In7.Cu" signal)
    (8 "In8.Cu" power)
    (9 "In9.Cu" signal)
    (10 "In10.Cu" power)
    (31 "B.Cu" signal)
    (32 "B.Adhes" user "B.Adhesive")
    (33 "F.Adhes" user "F.Adhesive")
    (34 "B.Paste" user)
    (35 "F.Paste" user)
    (36 "B.SilkS" user "B.Silkscreen")
    (37 "F.SilkS" user "F.Silkscreen")
    (38 "B.Mask" user)
    (39 "F.Mask" user)
    (40 "Dwgs.User" user "User.Drawings")
    (41 "Cmts.User" user "User.Comments")
    (42 "Eco1.User" user "User.Eco1")
    (43 "Eco2.User" user "User.Eco2")
    (44 "Edge.Cuts" user)
    (45 "Margin" user)
    (46 "B.CrtYd" user "B.Courtyard")
    (47 "F.CrtYd" user "F.Courtyard")
    (48 "B.Fab" user)
    (49 "F.Fab" user)
  )
	(footprint "data-center-rdimm-ddr4-tester-footprints:C_0201" (layer "B.Cu")
    (at 193.65 85.575 180)
    (descr "Capacitor SMD 0201")
    (tags "capacitor SMD 0201")
    (property "Author" "Antmicro")
    (property "Dielectric" "")
    (property "License" "Apache-2.0")
    (property "MPN" "CC0201KRX6S5BB104")
    (property "Manufacturer" "Yaego")
    (property "Sheetfile" "fpga-power.kicad_sch")
    (property "Sheetname" "FPGA power")
    (property "Val" "100n")
    (property "Voltage" "")
    (property "ki_description" " ")
    (attr smd)
    (fp_text reference "C21" (at -1.06 0.375) (layer "B.SilkS")
        (effects (font (size 0.7 0.7) (thickness 0.15)) (justify left bottom mirror))
    )
    (fp_text value "C_100n_0201" (at 0 -1.4) (layer "B.Fab") hide
        (effects (font (size 0.7 0.7) (thickness 0.15)) (justify left bottom mirror))
    )
    (fp_text user "${REFERENCE}" (at -0.72 -3.4) (layer "B.Fab") hide
        (effects (font (size 0.7 0.7) (thickness 0.15)) (justify left bottom mirror))
    )
    (fp_text user "Author: Antmicro" (at -0.72 -5.4) (layer "B.Fab") hide
        (effects (font (size 0.7 0.7) (thickness 0.15)) (justify left bottom mirror))
    )
    (fp_text user "License: Apache-2.0" (at -0.72 -4.4) (layer "B.Fab") hide
        (effects (font (size 0.7 0.7) (thickness 0.15)) (justify left bottom mirror))
    )
    (fp_rect (start -0.72 0.38) (end 0.72 -0.38)
      (stroke (width 0.05) (type solid)) (fill none) (layer "B.CrtYd"))
    (fp_rect (start 0.3 -0.15) (end -0.301 0.149)
      (stroke (width 0.15) (type solid)) (fill none) (layer "B.Fab"))
    (pad "" smd roundrect (at -0.349 0.002 180) (size 0.318 0.36) (layers "B.Paste") (roundrect_rratio 0.25))
    (pad "" smd roundrect (at 0.341 0.002 180) (size 0.318 0.36) (layers "B.Paste") (roundrect_rratio 0.25))
    (pad "1" smd roundrect (at -0.321 0.002 180) (size 0.46 0.4) (layers "B.Cu" "B.Mask") (roundrect_rratio 0.25)
      (net 77 "VDDQ") (pintype "passive"))
    (pad "2" smd roundrect (at 0.32 0.002 180) (size 0.46 0.4) (layers "B.Cu" "B.Mask") (roundrect_rratio 0.25)
      (net 9 "GND") (pintype "passive"))
  )
	(footprint "data-center-rdimm-ddr4-tester-footprints:C_0603_1608Metric" (layer "B.Cu")
    (at 179.236328 88.260008 180)
    (descr "Capacitor SMD 0603")
    (tags "capacitor 0603")
    (property "Author" "Antmicro")
    (property "Dielectric" "")
    (property "License" "Apache-2.0")
    (property "MPN" "GRM188R60J476ME15D")
    (property "Manufacturer" "Murata")
    (property "Sheetfile" "fpga-power.kicad_sch")
    (property "Sheetname" "FPGA power")
    (property "Val" "47u")
    (property "Voltage" "")
    (property "ki_description" " ")
    (attr smd)
    (fp_text reference "C23" (at -1.043672 0.780008) (layer "B.SilkS")
        (effects (font (size 0.7 0.7) (thickness 0.15)) (justify left bottom mirror))
    )
    (fp_text value "C_47u_0603" (at 0 -1.6) (layer "B.Fab") hide
        (effects (font (size 0.7 0.7) (thickness 0.15)) (justify left bottom mirror))
    )
    (fp_text user "${REFERENCE}" (at -1.682 -3.895) (layer "B.Fab") hide
        (effects (font (size 0.7 0.7) (thickness 0.15)) (justify left bottom mirror))
    )
    (fp_text user "Author: Antmicro" (at -1.682 -4.894) (layer "B.Fab") hide
        (effects (font (size 0.7 0.7) (thickness 0.15)) (justify left bottom mirror))
    )
    (fp_text user "License: Apache-2.0" (at -1.682 -5.895) (layer "B.Fab") hide
        (effects (font (size 0.7 0.7) (thickness 0.15)) (justify left bottom mirror))
    )
    (fp_line (start -0.3 -0.3) (end 0.3 -0.3)
      (stroke (width 0.15) (type solid)) (layer "B.SilkS"))
    (fp_line (start -0.3 0.3) (end 0.3 0.3)
      (stroke (width 0.15) (type solid)) (layer "B.SilkS"))
    (fp_rect (start -1.24 0.7) (end 1.24 -0.7)
      (stroke (width 0.05) (type solid)) (fill none) (layer "B.CrtYd"))
    (fp_rect (start -0.8 0.4) (end 0.8 -0.4)
      (stroke (width 0.15) (type solid)) (fill none) (layer "B.Fab"))
    (pad "1" smd roundrect (at -0.7 0 180) (size 0.6 0.8) (layers "B.Cu" "B.Paste" "B.Mask") (roundrect_rratio 0.2)
      (net 77 "VDDQ") (pintype "passive"))
    (pad "2" smd roundrect (at 0.7 0 180) (size 0.6 0.8) (layers "B.Cu" "B.Paste" "B.Mask") (roundrect_rratio 0.2)
      (net 9 "GND") (pintype "passive"))
  )
	(footprint "data-center-rdimm-ddr4-tester-footprints:C_0603_1608Metric" (layer "B.Cu")
    (at 194.5 78.65 90)
    (descr "Capacitor SMD 0603")
    (tags "capacitor 0603")
    (property "Author" "Antmicro")
    (property "Dielectric" "")
    (property "License" "Apache-2.0")
    (property "MPN" "GRM188R60J476ME15D")
    (property "Manufacturer" "Murata")
    (property "Sheetfile" "fpga-power.kicad_sch")
    (property "Sheetname" "FPGA power")
    (property "Val" "47u")
    (property "Voltage" "")
    (property "ki_description" " ")
    (attr smd)
    (fp_text reference "C24" (at 3.47 0.45 270) (layer "B.SilkS")
        (effects (font (size 0.7 0.7) (thickness 0.15)) (justify left bottom mirror))
    )
    (fp_text value "C_47u_0603" (at 0 -1.6 270) (layer "B.Fab") hide
        (effects (font (size 0.7 0.7) (thickness 0.15)) (justify left bottom mirror))
    )
    (fp_text user "${REFERENCE}" (at -1.682 -3.895 270) (layer "B.Fab") hide
        (effects (font (size 0.7 0.7) (thickness 0.15)) (justify left bottom mirror))
    )
    (fp_text user "Author: Antmicro" (at -1.682 -4.894 270) (layer "B.Fab") hide
        (effects (font (size 0.7 0.7) (thickness 0.15)) (justify left bottom mirror))
    )
    (fp_text user "License: Apache-2.0" (at -1.682 -5.895 270) (layer "B.Fab") hide
        (effects (font (size 0.7 0.7) (thickness 0.15)) (justify left bottom mirror))
    )
    (fp_line (start -0.3 -0.3) (end 0.3 -0.3)
      (stroke (width 0.15) (type solid)) (layer "B.SilkS"))
    (fp_line (start -0.3 0.3) (end 0.3 0.3)
      (stroke (width 0.15) (type solid)) (layer "B.SilkS"))
    (fp_rect (start -1.24 0.7) (end 1.24 -0.7)
      (stroke (width 0.05) (type solid)) (fill none) (layer "B.CrtYd"))
    (fp_rect (start -0.8 0.4) (end 0.8 -0.4)
      (stroke (width 0.15) (type solid)) (fill none) (layer "B.Fab"))
    (pad "1" smd roundrect (at -0.7 0 90) (size 0.6 0.8) (layers "B.Cu" "B.Paste" "B.Mask") (roundrect_rratio 0.2)
      (net 77 "VDDQ") (pintype "passive"))
    (pad "2" smd roundrect (at 0.7 0 90) (size 0.6 0.8) (layers "B.Cu" "B.Paste" "B.Mask") (roundrect_rratio 0.2)
      (net 9 "GND") (pintype "passive"))
  )
	(footprint "data-center-rdimm-ddr4-tester-footprints:C_0201" (layer "B.Cu")
    (at 188.186328 88.535008 -90)
    (descr "Capacitor SMD 0201")
    (tags "capacitor SMD 0201")
    (property "Author" "Antmicro")
    (property "Dielectric" "")
    (property "License" "Apache-2.0")
    (property "MPN" "CC0201KRX6S5BB104")
    (property "Manufacturer" "Yaego")
    (property "Sheetfile" "fpga-power.kicad_sch")
    (property "Sheetname" "FPGA power")
    (property "Val" "100n")
    (property "Voltage" "")
    (property "ki_description" " ")
    (attr smd)
    (fp_text reference "C47" (at -10.285008 -18.163672 90) (layer "B.SilkS")
        (effects (font (size 0.7 0.7) (thickness 0.15)) (justify left bottom mirror))
    )
    (fp_text value "C_100n_0201" (at 0 -1.4 90) (layer "B.Fab") hide
        (effects (font (size 0.7 0.7) (thickness 0.15)) (justify left bottom mirror))
    )
    (fp_text user "Author: Antmicro" (at -0.72 -5.4 90) (layer "B.Fab") hide
        (effects (font (size 0.7 0.7) (thickness 0.15)) (justify left bottom mirror))
    )
    (fp_text user "${REFERENCE}" (at -0.72 -3.4 90) (layer "B.Fab") hide
        (effects (font (size 0.7 0.7) (thickness 0.15)) (justify left bottom mirror))
    )
    (fp_text user "License: Apache-2.0" (at -0.72 -4.4 90) (layer "B.Fab") hide
        (effects (font (size 0.7 0.7) (thickness 0.15)) (justify left bottom mirror))
    )
    (fp_rect (start -0.72 0.38) (end 0.72 -0.38)
      (stroke (width 0.05) (type solid)) (fill none) (layer "B.CrtYd"))
    (fp_rect (start 0.3 -0.15) (end -0.301 0.149)
      (stroke (width 0.15) (type solid)) (fill none) (layer "B.Fab"))
    (pad "" smd roundrect (at -0.349 0.002 270) (size 0.318 0.36) (layers "B.Paste") (roundrect_rratio 0.25))
    (pad "" smd roundrect (at 0.341 0.002 270) (size 0.318 0.36) (layers "B.Paste") (roundrect_rratio 0.25))
    (pad "1" smd roundrect (at -0.321 0.002 270) (size 0.46 0.4) (layers "B.Cu" "B.Mask") (roundrect_rratio 0.25)
      (net 144 "1V8_SYS") (pintype "passive"))
    (pad "2" smd roundrect (at 0.32 0.002 270) (size 0.46 0.4) (layers "B.Cu" "B.Mask") (roundrect_rratio 0.25)
      (net 9 "GND") (pintype "passive"))
  )
	(footprint "data-center-rdimm-ddr4-tester-footprints:C_0201" (layer "B.Cu")
    (at 187.086328 93.410008 -90)
    (descr "Capacitor SMD 0201")
    (tags "capacitor SMD 0201")
    (property "Author" "Antmicro")
    (property "Dielectric" "")
    (property "License" "Apache-2.0")
    (property "MPN" "CC0201KRX6S5BB104")
    (property "Manufacturer" "Yaego")
    (property "Sheetfile" "fpga-power.kicad_sch")
    (property "Sheetname" "FPGA power")
    (property "Val" "100n")
    (property "Voltage" "")
    (property "ki_description" " ")
    (attr smd)
    (fp_text reference "C48" (at -10.220008 -18.493672 90) (layer "B.SilkS")
        (effects (font (size 0.7 0.7) (thickness 0.15)) (justify left bottom mirror))
    )
    (fp_text value "C_100n_0201" (at 0 -1.4 90) (layer "B.Fab") hide
        (effects (font (size 0.7 0.7) (thickness 0.15)) (justify left bottom mirror))
    )
    (fp_text user "Author: Antmicro" (at -0.72 -5.4 90) (layer "B.Fab") hide
        (effects (font (size 0.7 0.7) (thickness 0.15)) (justify left bottom mirror))
    )
    (fp_text user "License: Apache-2.0" (at -0.72 -4.4 90) (layer "B.Fab") hide
        (effects (font (size 0.7 0.7) (thickness 0.15)) (justify left bottom mirror))
    )
    (fp_text user "${REFERENCE}" (at -0.72 -3.4 90) (layer "B.Fab") hide
        (effects (font (size 0.7 0.7) (thickness 0.15)) (justify left bottom mirror))
    )
    (fp_rect (start -0.72 0.38) (end 0.72 -0.38)
      (stroke (width 0.05) (type solid)) (fill none) (layer "B.CrtYd"))
    (fp_rect (start 0.3 -0.15) (end -0.301 0.149)
      (stroke (width 0.15) (type solid)) (fill none) (layer "B.Fab"))
    (pad "" smd roundrect (at -0.349 0.002 270) (size 0.318 0.36) (layers "B.Paste") (roundrect_rratio 0.25))
    (pad "" smd roundrect (at 0.341 0.002 270) (size 0.318 0.36) (layers "B.Paste") (roundrect_rratio 0.25))
    (pad "1" smd roundrect (at -0.321 0.002 270) (size 0.46 0.4) (layers "B.Cu" "B.Mask") (roundrect_rratio 0.25)
      (net 144 "1V8_SYS") (pintype "passive"))
    (pad "2" smd roundrect (at 0.32 0.002 270) (size 0.46 0.4) (layers "B.Cu" "B.Mask") (roundrect_rratio 0.25)
      (net 9 "GND") (pintype "passive"))
  )
	(footprint "data-center-rdimm-ddr4-tester-footprints:C_0201" (layer "B.Cu")
    (at 187.186328 91.560008 90)
    (descr "Capacitor SMD 0201")
    (tags "capacitor SMD 0201")
    (property "Author" "Antmicro")
    (property "Dielectric" "")
    (property "License" "Apache-2.0")
    (property "MPN" "CC0201KRX6S5BB104")
    (property "Manufacturer" "Yaego")
    (property "Sheetfile" "fpga-power.kicad_sch")
    (property "Sheetname" "FPGA power")
    (property "Val" "100n")
    (property "Voltage" "")
    (property "ki_description" " ")
    (attr smd)
    (fp_text reference "C51" (at 10.240008 18.413672 270) (layer "B.SilkS")
        (effects (font (size 0.7 0.7) (thickness 0.15)) (justify left bottom mirror))
    )
    (fp_text value "C_100n_0201" (at 0 -1.4 270) (layer "B.Fab") hide
        (effects (font (size 0.7 0.7) (thickness 0.15)) (justify left bottom mirror))
    )
    (fp_text user "${REFERENCE}" (at -0.72 -3.4 270) (layer "B.Fab") hide
        (effects (font (size 0.7 0.7) (thickness 0.15)) (justify left bottom mirror))
    )
    (fp_text user "License: Apache-2.0" (at -0.72 -4.4 270) (layer "B.Fab") hide
        (effects (font (size 0.7 0.7) (thickness 0.15)) (justify left bottom mirror))
    )
    (fp_text user "Author: Antmicro" (at -0.72 -5.4 270) (layer "B.Fab") hide
        (effects (font (size 0.7 0.7) (thickness 0.15)) (justify left bottom mirror))
    )
    (fp_rect (start -0.72 0.38) (end 0.72 -0.38)
      (stroke (width 0.05) (type solid)) (fill none) (layer "B.CrtYd"))
    (fp_rect (start 0.3 -0.15) (end -0.301 0.149)
      (stroke (width 0.15) (type solid)) (fill none) (layer "B.Fab"))
    (pad "" smd roundrect (at -0.349 0.002 90) (size 0.318 0.36) (layers "B.Paste") (roundrect_rratio 0.25))
    (pad "" smd roundrect (at 0.341 0.002 90) (size 0.318 0.36) (layers "B.Paste") (roundrect_rratio 0.25))
    (pad "1" smd roundrect (at -0.321 0.002 90) (size 0.46 0.4) (layers "B.Cu" "B.Mask") (roundrect_rratio 0.25)
      (net 144 "1V8_SYS") (pintype "passive"))
    (pad "2" smd roundrect (at 0.32 0.002 90) (size 0.46 0.4) (layers "B.Cu" "B.Mask") (roundrect_rratio 0.25)
      (net 9 "GND") (pintype "passive"))
  )
	(footprint "data-center-rdimm-ddr4-tester-footprints:C_0201" (layer "B.Cu")
    (at 189.925 98.15 90)
    (descr "Capacitor SMD 0201")
    (tags "capacitor SMD 0201")
    (property "Author" "Antmicro")
    (property "Dielectric" "")
    (property "License" "Apache-2.0")
    (property "MPN" "CC0201KRX6S5BB104")
    (property "Manufacturer" "Yaego")
    (property "Sheetfile" "fpga-power.kicad_sch")
    (property "Sheetname" "FPGA power")
    (property "Val" "100n")
    (property "Voltage" "")
    (property "ki_description" " ")
    (attr smd)
    (fp_text reference "C53" (at 1.06 1.235 270) (layer "B.SilkS")
        (effects (font (size 0.7 0.7) (thickness 0.15)) (justify left bottom mirror))
    )
    (fp_text value "C_100n_0201" (at 0 -1.4 270) (layer "B.Fab") hide
        (effects (font (size 0.7 0.7) (thickness 0.15)) (justify left bottom mirror))
    )
    (fp_text user "Author: Antmicro" (at -0.72 -5.4 270) (layer "B.Fab") hide
        (effects (font (size 0.7 0.7) (thickness 0.15)) (justify left bottom mirror))
    )
    (fp_text user "License: Apache-2.0" (at -0.72 -4.4 270) (layer "B.Fab") hide
        (effects (font (size 0.7 0.7) (thickness 0.15)) (justify left bottom mirror))
    )
    (fp_text user "${REFERENCE}" (at -0.72 -3.4 270) (layer "B.Fab") hide
        (effects (font (size 0.7 0.7) (thickness 0.15)) (justify left bottom mirror))
    )
    (fp_rect (start -0.72 0.38) (end 0.72 -0.38)
      (stroke (width 0.05) (type solid)) (fill none) (layer "B.CrtYd"))
    (fp_rect (start 0.3 -0.15) (end -0.301 0.149)
      (stroke (width 0.15) (type solid)) (fill none) (layer "B.Fab"))
    (pad "" smd roundrect (at -0.349 0.002 90) (size 0.318 0.36) (layers "B.Paste") (roundrect_rratio 0.25))
    (pad "" smd roundrect (at 0.341 0.002 90) (size 0.318 0.36) (layers "B.Paste") (roundrect_rratio 0.25))
    (pad "1" smd roundrect (at -0.321 0.002 90) (size 0.46 0.4) (layers "B.Cu" "B.Mask") (roundrect_rratio 0.25)
      (net 144 "1V8_SYS") (pintype "passive"))
    (pad "2" smd roundrect (at 0.32 0.002 90) (size 0.46 0.4) (layers "B.Cu" "B.Mask") (roundrect_rratio 0.25)
      (net 9 "GND") (pintype "passive"))
  )
	(footprint "data-center-rdimm-ddr4-tester-footprints:C_0201" (layer "B.Cu")
    (at 184.186328 91.560008 90)
    (descr "Capacitor SMD 0201")
    (tags "capacitor SMD 0201")
    (property "Author" "Antmicro")
    (property "Dielectric" "")
    (property "License" "Apache-2.0")
    (property "MPN" "CC0201KRX6S5BB104")
    (property "Manufacturer" "Yaego")
    (property "Sheetfile" "fpga-power.kicad_sch")
    (property "Sheetname" "FPGA power")
    (property "Val" "100n")
    (property "Voltage" "")
    (property "ki_description" " ")
    (attr smd)
    (fp_text reference "C55" (at 10.340008 18.373672 270) (layer "B.SilkS")
        (effects (font (size 0.7 0.7) (thickness 0.15)) (justify left bottom mirror))
    )
    (fp_text value "C_100n_0201" (at 0 -1.4 270) (layer "B.Fab") hide
        (effects (font (size 0.7 0.7) (thickness 0.15)) (justify left bottom mirror))
    )
    (fp_text user "License: Apache-2.0" (at -0.72 -4.4 270) (layer "B.Fab") hide
        (effects (font (size 0.7 0.7) (thickness 0.15)) (justify left bottom mirror))
    )
    (fp_text user "${REFERENCE}" (at -0.72 -3.4 270) (layer "B.Fab") hide
        (effects (font (size 0.7 0.7) (thickness 0.15)) (justify left bottom mirror))
    )
    (fp_text user "Author: Antmicro" (at -0.72 -5.4 270) (layer "B.Fab") hide
        (effects (font (size 0.7 0.7) (thickness 0.15)) (justify left bottom mirror))
    )
    (fp_rect (start -0.72 0.38) (end 0.72 -0.38)
      (stroke (width 0.05) (type solid)) (fill none) (layer "B.CrtYd"))
    (fp_rect (start 0.3 -0.15) (end -0.301 0.149)
      (stroke (width 0.15) (type solid)) (fill none) (layer "B.Fab"))
    (pad "" smd roundrect (at -0.349 0.002 90) (size 0.318 0.36) (layers "B.Paste") (roundrect_rratio 0.25))
    (pad "" smd roundrect (at 0.341 0.002 90) (size 0.318 0.36) (layers "B.Paste") (roundrect_rratio 0.25))
    (pad "1" smd roundrect (at -0.321 0.002 90) (size 0.46 0.4) (layers "B.Cu" "B.Mask") (roundrect_rratio 0.25)
      (net 144 "1V8_SYS") (pintype "passive"))
    (pad "2" smd roundrect (at 0.32 0.002 90) (size 0.46 0.4) (layers "B.Cu" "B.Mask") (roundrect_rratio 0.25)
      (net 9 "GND") (pintype "passive"))
  )
	(footprint "data-center-rdimm-ddr4-tester-footprints:C_0201" (layer "B.Cu")
    (at 185.186328 86.560008 -90)
    (descr "Capacitor SMD 0201")
    (tags "capacitor SMD 0201")
    (property "Author" "Antmicro")
    (property "Dielectric" "")
    (property "License" "Apache-2.0")
    (property "MPN" "CC0201KRX6S5BB104")
    (property "Manufacturer" "Yaego")
    (property "Sheetfile" "fpga-power.kicad_sch")
    (property "Sheetname" "FPGA power")
    (property "Val" "100n")
    (property "Voltage" "")
    (property "ki_description" " ")
    (attr smd)
    (fp_text reference "C56" (at -10.320008 -17.903672 90) (layer "B.SilkS")
        (effects (font (size 0.7 0.7) (thickness 0.15)) (justify left bottom mirror))
    )
    (fp_text value "C_100n_0201" (at 0 -1.4 90) (layer "B.Fab") hide
        (effects (font (size 0.7 0.7) (thickness 0.15)) (justify left bottom mirror))
    )
    (fp_text user "${REFERENCE}" (at -0.72 -3.4 90) (layer "B.Fab") hide
        (effects (font (size 0.7 0.7) (thickness 0.15)) (justify left bottom mirror))
    )
    (fp_text user "License: Apache-2.0" (at -0.72 -4.4 90) (layer "B.Fab") hide
        (effects (font (size 0.7 0.7) (thickness 0.15)) (justify left bottom mirror))
    )
    (fp_text user "Author: Antmicro" (at -0.72 -5.4 90) (layer "B.Fab") hide
        (effects (font (size 0.7 0.7) (thickness 0.15)) (justify left bottom mirror))
    )
    (fp_rect (start -0.72 0.38) (end 0.72 -0.38)
      (stroke (width 0.05) (type solid)) (fill none) (layer "B.CrtYd"))
    (fp_rect (start 0.3 -0.15) (end -0.301 0.149)
      (stroke (width 0.15) (type solid)) (fill none) (layer "B.Fab"))
    (pad "" smd roundrect (at -0.349 0.002 270) (size 0.318 0.36) (layers "B.Paste") (roundrect_rratio 0.25))
    (pad "" smd roundrect (at 0.341 0.002 270) (size 0.318 0.36) (layers "B.Paste") (roundrect_rratio 0.25))
    (pad "1" smd roundrect (at -0.321 0.002 270) (size 0.46 0.4) (layers "B.Cu" "B.Mask") (roundrect_rratio 0.25)
      (net 144 "1V8_SYS") (pintype "passive"))
    (pad "2" smd roundrect (at 0.32 0.002 270) (size 0.46 0.4) (layers "B.Cu" "B.Mask") (roundrect_rratio 0.25)
      (net 9 "GND") (pintype "passive"))
  )
)
